(kicad_pcb
	(version 20260206)
	(generator "pcbnew")
	(generator_version "10.0")
	(general
		(thickness 1.6)
		(legacy_teardrops no)
	)
	(paper "A4")
	(title_block
		(title "v2-pdb — ms_pdb_v2.brd")
		(comment 1 "Open CloudServer (Microsoft) / footprints 252-257 of 348")
	)
	(layers
		(0 "F.Cu" signal "TOP")
		(4 "In1.Cu" signal "GND")
		(6 "In2.Cu" signal "IN1")
		(8 "In3.Cu" signal "VCC")
		(10 "In4.Cu" signal "VCC1")
		(12 "In5.Cu" signal "IN2")
		(14 "In6.Cu" signal "GND1")
		(2 "B.Cu" signal "BOTTOM")
		(9 "F.Adhes" user "F.Adhesive")
		(11 "B.Adhes" user "B.Adhesive")
		(13 "F.Paste" user "Package Geometry/Pastemask Top")
		(15 "B.Paste" user "Package Geometry/Pastemask Bottom")
		(5 "F.SilkS" user "Ref Des/Silkscreen Top")
		(7 "B.SilkS" user "Ref Des/Silkscreen Bottom")
		(1 "F.Mask" user "Board Geometry/Soldermask Top")
		(3 "B.Mask" user "Board Geometry/Soldermask Bottom")
		(17 "Dwgs.User" user "User.Drawings")
		(19 "Cmts.User" user "User.Comments")
		(21 "Eco1.User" user "User.Eco1")
		(23 "Eco2.User" user "User.Eco2")
		(25 "Edge.Cuts" user "Board Geometry/Outline")
		(27 "Margin" user)
		(31 "F.CrtYd" user "Package Geometry/Place Bound Top")
		(29 "B.CrtYd" user "Package Geometry/Place Bound Bottom")
		(35 "F.Fab" user "Ref Des/Assembly Top")
		(33 "B.Fab" user "Ref Des/Assembly Bottom")
	)
	(footprint ""
		(layer "F.Cu")
		(at 27.347672 -108.630466 -90)
		(property "Reference" "R93"
			(at -0.391414 1.160526 90)
			(unlocked yes)
			(layer "F.SilkS")
			(effects
				(font
					(size 0.7874 0.5842)
					(thickness 0.1524)
				)
				(justify left)
			)
		)
		(property "Value" ""
			(at 0 0 270)
			(layer "F.Fab")
			(effects
				(font
					(size 1.27 1.27)
				)
			)
		)
		(duplicate_pad_numbers_are_jumpers no)
		(fp_line
			(start -0.7874 0.4064)
			(end -0.7874 -0.4064)
			(stroke
				(width 0.1524)
				(type default)
			)
			(layer "F.SilkS")
		)
		(fp_line
			(start 0.7874 0.4064)
			(end -0.7874 0.4064)
			(stroke
				(width 0.1524)
				(type default)
			)
			(layer "F.SilkS")
		)
		(fp_line
			(start -0.7874 -0.4064)
			(end 0.7874 -0.4064)
			(stroke
				(width 0.1524)
				(type default)
			)
			(layer "F.SilkS")
		)
		(fp_line
			(start 0.7874 -0.4064)
			(end 0.7874 0.4064)
			(stroke
				(width 0.1524)
				(type default)
			)
			(layer "F.SilkS")
		)
		(fp_poly
			(pts
				(xy -0.508 0.2794) (xy -0.508 0.2286) (xy -0.635 0.2286) (xy -0.635 -0.254) (xy -0.5334 -0.254)
				(xy -0.5334 -0.2794) (xy 0.5334 -0.2794) (xy 0.5334 -0.254) (xy 0.635 -0.254) (xy 0.635 0.254) (xy 0.5334 0.254)
				(xy 0.5334 0.2794)
			)
			(stroke
				(width 0)
				(type default)
			)
			(fill no)
			(layer "F.CrtYd")
		)
		(pad "1" smd rect
			(at 0.40005 0 270)
			(size 0.4572 0.508)
			(layers "F.Cu" "F.Mask" "F.Paste")
			(net "PSU2_REMOTE_N")
		)
		(pad "2" smd rect
			(at -0.40005 0 270)
			(size 0.4572 0.508)
			(layers "F.Cu" "F.Mask" "F.Paste")
			(net "PSU2_REMOTE_R_N")
		)
	)
	(footprint ""
		(layer "F.Cu")
		(at 13.964666 -105.537 -90)
		(property "Reference" "J27"
			(at -4.11607 4.406138 0)
			(unlocked yes)
			(layer "F.SilkS")
			(effects
				(font
					(size 0.7874 0.5842)
					(thickness 0.1524)
				)
				(justify left)
			)
		)
		(property "Value" ""
			(at 0 0 270)
			(layer "F.Fab")
			(effects
				(font
					(size 1.27 1.27)
				)
			)
		)
		(duplicate_pad_numbers_are_jumpers no)
		(fp_line
			(start -3.370072 12.830048)
			(end -3.370072 -3.81)
			(stroke
				(width 0.1524)
				(type default)
			)
			(layer "F.SilkS")
		)
		(fp_line
			(start 12.260072 12.830048)
			(end -3.370072 12.830048)
			(stroke
				(width 0.1524)
				(type default)
			)
			(layer "F.SilkS")
		)
		(fp_line
			(start -3.370072 -3.81)
			(end 12.260072 -3.81)
			(stroke
				(width 0.1524)
				(type default)
			)
			(layer "F.SilkS")
		)
		(fp_line
			(start 12.260072 -3.81)
			(end 12.260072 12.830048)
			(stroke
				(width 0.1524)
				(type default)
			)
			(layer "F.SilkS")
		)
		(fp_poly
			(pts
				(xy -0.073914 -4.222496) (xy -0.7874 -5.649468) (xy 0.639572 -5.649468)
			)
			(stroke
				(width 0)
				(type default)
			)
			(fill yes)
			(layer "F.SilkS")
		)
		(fp_poly
			(pts
				(xy -0.762 0.762) (xy 8.382 0.762) (xy 8.382 -1.8034) (xy 9.652 -1.8034) (xy 9.652 -3.302) (xy 0.508 -3.302)
				(xy 0.508 -0.762) (xy -0.762 -0.762)
			)
			(stroke
				(width 0)
				(type default)
			)
			(fill no)
			(layer "B.CrtYd")
		)
		(fp_poly
			(pts
				(arc
					(start -1.27 4.4196)
					(mid -1.27 8.2804)
					(end -1.27 4.4196)
				)
			)
			(stroke
				(width 0)
				(type default)
			)
			(fill no)
			(layer "B.CrtYd")
		)
		(fp_poly
			(pts
				(arc
					(start 10.16 4.4196)
					(mid 10.16 8.2804)
					(end 10.16 4.4196)
				)
			)
			(stroke
				(width 0)
				(type default)
			)
			(fill no)
			(layer "B.CrtYd")
		)
		(fp_poly
			(pts
				(xy -3.370072 12.830048) (xy 12.260072 12.830048) (xy 12.260072 -3.81) (xy -3.370072 -3.81)
			)
			(stroke
				(width 0)
				(type default)
			)
			(fill no)
			(layer "F.CrtYd")
		)
		(fp_line
			(start -3.370072 12.830048)
			(end -3.370072 -3.81)
			(stroke
				(width 0.1)
				(type default)
			)
			(layer "F.Fab")
		)
		(fp_line
			(start 12.260072 12.830048)
			(end -3.370072 12.830048)
			(stroke
				(width 0.1)
				(type default)
			)
			(layer "F.Fab")
		)
		(fp_line
			(start -3.370072 -3.81)
			(end 12.260072 -3.81)
			(stroke
				(width 0.1)
				(type default)
			)
			(layer "F.Fab")
		)
		(fp_line
			(start 12.260072 -3.81)
			(end 12.260072 12.830048)
			(stroke
				(width 0.1)
				(type default)
			)
			(layer "F.Fab")
		)
		(fp_poly
			(pts
				(xy -3.576828 0) (xy -5.0038 0.713486) (xy -5.0038 -0.713486)
			)
			(stroke
				(width 0)
				(type default)
			)
			(fill yes)
			(layer "F.Fab")
		)
		(fp_text user "1"
			(at -4.192016 0.242062 0)
			(unlocked yes)
			(layer "F.SilkS")
			(effects
				(font
					(size 0.7874 0.5842)
					(thickness 0.1524)
				)
			)
		)
		(fp_text user "7"
			(at 13.095224 -0.165354 0)
			(unlocked yes)
			(layer "F.SilkS")
			(effects
				(font
					(size 0.7874 0.5842)
					(thickness 0.1524)
				)
			)
		)
		(fp_text user "2"
			(at -4.021328 -2.464308 0)
			(unlocked yes)
			(layer "F.SilkS")
			(effects
				(font
					(size 0.7874 0.5842)
					(thickness 0.1524)
				)
			)
		)
		(fp_text user "8"
			(at 13.032486 -2.6035 0)
			(unlocked yes)
			(layer "F.SilkS")
			(effects
				(font
					(size 0.7874 0.5842)
					(thickness 0.1524)
				)
			)
		)
		(fp_text user "1"
			(at -1.484376 -0.020066 0)
			(unlocked yes)
			(layer "B.SilkS")
			(effects
				(font
					(size 0.7874 0.5842)
					(thickness 0.1524)
				)
				(justify mirror)
			)
		)
		(fp_text user "7"
			(at 9.450578 -0.041148 0)
			(unlocked yes)
			(layer "B.SilkS")
			(effects
				(font
					(size 0.7874 0.5842)
					(thickness 0.1524)
				)
				(justify mirror)
			)
		)
		(fp_text user "8"
			(at 10.720578 -2.682748 0)
			(unlocked yes)
			(layer "B.SilkS")
			(effects
				(font
					(size 0.7874 0.5842)
					(thickness 0.1524)
				)
				(justify mirror)
			)
		)
		(fp_text user "2"
			(at -0.188976 -2.687066 0)
			(unlocked yes)
			(layer "B.SilkS")
			(effects
				(font
					(size 0.7874 0.5842)
					(thickness 0.1524)
				)
				(justify mirror)
			)
		)
		(fp_text user "7"
			(at 8.8138 0.238252 270)
			(unlocked yes)
			(layer "B.Fab")
			(effects
				(font
					(size 0.7874 0.5842)
					(thickness 0.000001)
				)
				(justify mirror)
			)
		)
		(fp_text user "1"
			(at -1.2954 0.085852 270)
			(unlocked yes)
			(layer "B.Fab")
			(effects
				(font
					(size 0.7874 0.5842)
					(thickness 0.000001)
				)
				(justify mirror)
			)
		)
		(fp_text user "8"
			(at 10.0838 -2.403348 270)
			(unlocked yes)
			(layer "B.Fab")
			(effects
				(font
					(size 0.7874 0.5842)
					(thickness 0.000001)
				)
				(justify mirror)
			)
		)
		(fp_text user "2"
			(at 0 -2.581148 270)
			(unlocked yes)
			(layer "B.Fab")
			(effects
				(font
					(size 0.7874 0.5842)
					(thickness 0.000001)
				)
				(justify mirror)
			)
		)
		(fp_text user "7"
			(at 12.7762 -0.091948 270)
			(unlocked yes)
			(layer "F.Fab")
			(effects
				(font
					(size 0.7874 0.5842)
					(thickness 0.000001)
				)
			)
		)
		(fp_text user "1"
			(at -3.9116 -0.930148 270)
			(unlocked yes)
			(layer "F.Fab")
			(effects
				(font
					(size 0.7874 0.5842)
					(thickness 0.000001)
				)
			)
		)
		(fp_text user "2"
			(at -3.9624 -2.428748 270)
			(unlocked yes)
			(layer "F.Fab")
			(effects
				(font
					(size 0.7874 0.5842)
					(thickness 0.000001)
				)
			)
		)
		(fp_text user "8"
			(at 12.7762 -2.555748 270)
			(unlocked yes)
			(layer "F.Fab")
			(effects
				(font
					(size 0.7874 0.5842)
					(thickness 0.000001)
				)
			)
		)
		(pad "" np_thru_hole circle
			(at -1.27 6.35 270)
			(size 3.3528 3.3528)
			(drill 3.3528)
			(layers "*.Cu" "*.Mask")
			(clearance 0.381)
			(thermal_gap 0.381)
		)
		(pad "" np_thru_hole circle
			(at 10.16 6.35 270)
			(size 3.3528 3.3528)
			(drill 3.3528)
			(layers "*.Cu" "*.Mask")
			(clearance 0.381)
			(thermal_gap 0.381)
		)
		(pad "1" thru_hole rect
			(at 0 0 270)
			(size 1.397 1.397)
			(drill 0.9906)
			(layers "*.Cu" "*.Mask")
			(remove_unused_layers no)
			(net "UART_RTS_P6_L_N")
			(clearance 0.0508)
			(thermal_gap 0.0508)
			(padstack
				(mode front_inner_back)
				(layer "Inner"
					(shape circle)
					(size 1.397 1.397)
					(clearance 0.0508)
				)
				(layer "B.Cu"
					(shape rect)
					(size 1.397 1.397)
					(clearance 0.0508)
				)
			)
		)
		(pad "2" thru_hole circle
			(at 1.27 -2.54 270)
			(size 1.397 1.397)
			(drill 0.9906)
			(layers "*.Cu" "*.Mask")
			(remove_unused_layers no)
			(net "UART_DSR_P6_L_N")
			(clearance 0.0508)
			(thermal_gap 0.0508)
		)
		(pad "3" thru_hole circle
			(at 2.54 0 270)
			(size 1.397 1.397)
			(drill 0.9906)
			(layers "*.Cu" "*.Mask")
			(remove_unused_layers no)
			(net "UART_RX_P6_L")
			(clearance 0.0508)
			(thermal_gap 0.0508)
		)
		(pad "4" thru_hole circle
			(at 3.81 -2.54 270)
			(size 1.397 1.397)
			(drill 0.9906)
			(layers "*.Cu" "*.Mask")
			(remove_unused_layers no)
			(net "UART_RI_P6_L_N")
			(clearance 0.0508)
			(thermal_gap 0.0508)
		)
		(pad "5" thru_hole circle
			(at 5.08 0 270)
			(size 1.397 1.397)
			(drill 0.9906)
			(layers "*.Cu" "*.Mask")
			(remove_unused_layers no)
			(net "GND")
			(clearance 0.0508)
			(thermal_gap 0.0508)
		)
		(pad "6" thru_hole circle
			(at 6.35 -2.54 270)
			(size 1.397 1.397)
			(drill 0.9906)
			(layers "*.Cu" "*.Mask")
			(remove_unused_layers no)
			(net "UART_TX_P6_L")
			(clearance 0.0508)
			(thermal_gap 0.0508)
		)
		(pad "7" thru_hole circle
			(at 7.62 0 270)
			(size 1.397 1.397)
			(drill 0.9906)
			(layers "*.Cu" "*.Mask")
			(remove_unused_layers no)
			(net "UART_DTR_P6_L_N")
			(clearance 0.0508)
			(thermal_gap 0.0508)
		)
		(pad "8" thru_hole circle
			(at 8.89 -2.54 270)
			(size 1.397 1.397)
			(drill 0.9906)
			(layers "*.Cu" "*.Mask")
			(remove_unused_layers no)
			(net "UART_CTS_P6_L_N")
			(clearance 0.0508)
			(thermal_gap 0.0508)
		)
		(zone
			(layers "F.Cu" "B.Cu" "In1.Cu" "In2.Cu" "In3.Cu" "In4.Cu" "In5.Cu" "In6.Cu")
			(hatch none 0.5)
			(connect_pads
				(clearance 0)
			)
			(min_thickness 0.25)
			(keepout
				(tracks not_allowed)
				(vias allowed)
				(pads allowed)
				(copperpour not_allowed)
				(footprints allowed)
			)
			(placement
				(enabled no)
				(sheetname "")
			)
			(fill
				(thermal_gap 0.5)
				(thermal_bridge_width 0.5)
				(island_removal_mode 0)
			)
			(polygon
				(pts
					(arc
						(start 9.697466 -106.807)
						(mid 5.531866 -106.807)
						(end 9.697466 -106.807)
					)
				)
			)
		)
		(zone
			(layers "F.Cu" "B.Cu" "In1.Cu" "In2.Cu" "In3.Cu" "In4.Cu" "In5.Cu" "In6.Cu")
			(hatch none 0.5)
			(connect_pads
				(clearance 0)
			)
			(min_thickness 0.25)
			(keepout
				(tracks not_allowed)
				(vias allowed)
				(pads allowed)
				(copperpour not_allowed)
				(footprints allowed)
			)
			(placement
				(enabled no)
				(sheetname "")
			)
			(fill
				(thermal_gap 0.5)
				(thermal_bridge_width 0.5)
				(island_removal_mode 0)
			)
			(polygon
				(pts
					(arc
						(start 9.697466 -95.377)
						(mid 5.531866 -95.377)
						(end 9.697466 -95.377)
					)
				)
			)
		)
	)
	(footprint ""
		(layer "F.Cu")
		(at 72.157844 -419.796722 -90)
		(property "Reference" "C64"
			(at 2.880106 -0.214376 90)
			(unlocked yes)
			(layer "F.SilkS")
			(effects
				(font
					(size 0.7874 0.5842)
					(thickness 0.1524)
				)
			)
		)
		(property "Value" ""
			(at 0 0 270)
			(layer "F.Fab")
			(effects
				(font
					(size 1.27 1.27)
				)
			)
		)
		(duplicate_pad_numbers_are_jumpers no)
		(fp_line
			(start -1.2954 0.5842)
			(end -1.2954 -0.5842)
			(stroke
				(width 0.1524)
				(type default)
			)
			(layer "F.SilkS")
		)
		(fp_line
			(start 1.2954 0.5842)
			(end -1.2954 0.5842)
			(stroke
				(width 0.1524)
				(type default)
			)
			(layer "F.SilkS")
		)
		(fp_line
			(start -1.2954 -0.5842)
			(end 1.2954 -0.5842)
			(stroke
				(width 0.1524)
				(type default)
			)
			(layer "F.SilkS")
		)
		(fp_line
			(start 0 -0.5842)
			(end 0 0.5842)
			(stroke
				(width 0.1524)
				(type default)
			)
			(layer "F.SilkS")
		)
		(fp_line
			(start 1.2954 -0.5842)
			(end 1.2954 0.5842)
			(stroke
				(width 0.1524)
				(type default)
			)
			(layer "F.SilkS")
		)
		(fp_poly
			(pts
				(xy 0.8636 -0.4572) (xy 0.8636 -0.3556) (xy 1.143 -0.3556) (xy 1.143 0.3556) (xy 0.8636 0.3556)
				(xy 0.8636 0.4572) (xy -0.8636 0.4572) (xy -0.8636 0.3556) (xy -1.143 0.3556) (xy -1.143 -0.3556)
				(xy -0.8636 -0.3556) (xy -0.8636 -0.4572)
			)
			(stroke
				(width 0)
				(type default)
			)
			(fill no)
			(layer "F.CrtYd")
		)
		(fp_line
			(start -0.884936 0.504952)
			(end -0.884936 -0.504952)
			(stroke
				(width 0.1)
				(type default)
			)
			(layer "F.Fab")
		)
		(fp_line
			(start 0.884936 0.504952)
			(end -0.884936 0.504952)
			(stroke
				(width 0.1)
				(type default)
			)
			(layer "F.Fab")
		)
		(fp_line
			(start -0.884936 -0.504952)
			(end 0.884936 -0.504952)
			(stroke
				(width 0.1)
				(type default)
			)
			(layer "F.Fab")
		)
		(fp_line
			(start 0.884936 -0.504952)
			(end 0.884936 0.504952)
			(stroke
				(width 0.1)
				(type default)
			)
			(layer "F.Fab")
		)
		(pad "1" smd rect
			(at 0.7366 0)
			(size 0.7112 0.8128)
			(layers "F.Cu" "F.Mask" "F.Paste")
			(net "P12V")
		)
		(pad "2" smd rect
			(at -0.7366 0)
			(size 0.7112 0.8128)
			(layers "F.Cu" "F.Mask" "F.Paste")
			(net "GND")
		)
	)
	(footprint ""
		(layer "F.Cu")
		(at 74.709782 -330.332588 -90)
		(property "Reference" "C52"
			(at 3.323336 -0.058674 90)
			(unlocked yes)
			(layer "F.SilkS")
			(effects
				(font
					(size 0.7874 0.5842)
					(thickness 0.1524)
				)
				(justify left)
			)
		)
		(property "Value" ""
			(at 0 0 270)
			(layer "F.Fab")
			(effects
				(font
					(size 1.27 1.27)
				)
			)
		)
		(duplicate_pad_numbers_are_jumpers no)
		(fp_line
			(start -0.7874 0.4064)
			(end -0.7874 -0.4064)
			(stroke
				(width 0.1524)
				(type default)
			)
			(layer "F.SilkS")
		)
		(fp_line
			(start 0.7874 0.4064)
			(end -0.7874 0.4064)
			(stroke
				(width 0.1524)
				(type default)
			)
			(layer "F.SilkS")
		)
		(fp_line
			(start 0 0.381)
			(end 0 -0.381)
			(stroke
				(width 0.1524)
				(type default)
			)
			(layer "F.SilkS")
		)
		(fp_line
			(start -0.7874 -0.4064)
			(end 0.7874 -0.4064)
			(stroke
				(width 0.1524)
				(type default)
			)
			(layer "F.SilkS")
		)
		(fp_line
			(start 0.7874 -0.4064)
			(end 0.7874 0.4064)
			(stroke
				(width 0.1524)
				(type default)
			)
			(layer "F.SilkS")
		)
		(fp_poly
			(pts
				(xy -0.5334 0.254) (xy -0.635 0.254) (xy -0.635 0.2286) (xy -0.635 -0.254) (xy -0.5334 -0.254) (xy -0.5334 -0.2794)
				(xy 0.5334 -0.2794) (xy 0.5334 -0.254) (xy 0.635 -0.254) (xy 0.635 0.254) (xy 0.5334 0.254) (xy 0.5334 0.2794)
				(xy -0.508 0.2794) (xy -0.5334 0.2794)
			)
			(stroke
				(width 0)
				(type default)
			)
			(fill no)
			(layer "F.CrtYd")
		)
		(pad "1" smd rect
			(at 0.40005 0 270)
			(size 0.4572 0.508)
			(layers "F.Cu" "F.Mask" "F.Paste")
			(net "P12V")
		)
		(pad "2" smd rect
			(at -0.40005 0 270)
			(size 0.4572 0.508)
			(layers "F.Cu" "F.Mask" "F.Paste")
			(net "GND")
		)
	)
	(footprint ""
		(layer "F.Cu")
		(at 26.732484 -456.748896)
		(property "Reference" "R139"
			(at -3.883914 0.13208 0)
			(unlocked yes)
			(layer "F.SilkS")
			(effects
				(font
					(size 0.7874 0.5842)
					(thickness 0.1524)
				)
				(justify left)
			)
		)
		(property "Value" ""
			(at 0 0 0)
			(layer "F.Fab")
			(effects
				(font
					(size 1.27 1.27)
				)
			)
		)
		(duplicate_pad_numbers_are_jumpers no)
		(fp_line
			(start -0.7874 -0.4064)
			(end 0.7874 -0.4064)
			(stroke
				(width 0.1524)
				(type default)
			)
			(layer "F.SilkS")
		)
		(fp_line
			(start -0.7874 0.4064)
			(end -0.7874 -0.4064)
			(stroke
				(width 0.1524)
				(type default)
			)
			(layer "F.SilkS")
		)
		(fp_line
			(start 0.7874 -0.4064)
			(end 0.7874 0.4064)
			(stroke
				(width 0.1524)
				(type default)
			)
			(layer "F.SilkS")
		)
		(fp_line
			(start 0.7874 0.4064)
			(end -0.7874 0.4064)
			(stroke
				(width 0.1524)
				(type default)
			)
			(layer "F.SilkS")
		)
		(fp_poly
			(pts
				(xy -0.508 0.2794) (xy -0.508 0.2286) (xy -0.635 0.2286) (xy -0.635 -0.254) (xy -0.5334 -0.254)
				(xy -0.5334 -0.2794) (xy 0.5334 -0.2794) (xy 0.5334 -0.254) (xy 0.635 -0.254) (xy 0.635 0.254) (xy 0.5334 0.254)
				(xy 0.5334 0.2794)
			)
			(stroke
				(width 0)
				(type default)
			)
			(fill no)
			(layer "F.CrtYd")
		)
		(pad "1" smd rect
			(at 0.40005 0)
			(size 0.4572 0.508)
			(layers "F.Cu" "F.Mask" "F.Paste")
			(net "PSU6_CSAHRE")
		)
		(pad "2" smd rect
			(at -0.40005 0)
			(size 0.4572 0.508)
			(layers "F.Cu" "F.Mask" "F.Paste")
			(net "PSU_CSAHRE")
		)
	)
	(footprint ""
		(layer "F.Cu")
		(at 25.857708 -365.50092)
		(property "Reference" "R79"
			(at -3.917442 -0.225298 0)
			(unlocked yes)
			(layer "F.SilkS")
			(effects
				(font
					(size 0.7874 0.5842)
					(thickness 0.1524)
				)
				(justify left)
			)
		)
		(property "Value" ""
			(at 0 0 0)
			(layer "F.Fab")
			(effects
				(font
					(size 1.27 1.27)
				)
			)
		)
		(duplicate_pad_numbers_are_jumpers no)
		(fp_line
			(start -0.7874 -0.4064)
			(end 0.7874 -0.4064)
			(stroke
				(width 0.1524)
				(type default)
			)
			(layer "F.SilkS")
		)
		(fp_line
			(start -0.7874 0.4064)
			(end -0.7874 -0.4064)
			(stroke
				(width 0.1524)
				(type default)
			)
			(layer "F.SilkS")
		)
		(fp_line
			(start 0.7874 -0.4064)
			(end 0.7874 0.4064)
			(stroke
				(width 0.1524)
				(type default)
			)
			(layer "F.SilkS")
		)
		(fp_line
			(start 0.7874 0.4064)
			(end -0.7874 0.4064)
			(stroke
				(width 0.1524)
				(type default)
			)
			(layer "F.SilkS")
		)
		(fp_poly
			(pts
				(xy -0.508 0.2794) (xy -0.508 0.2286) (xy -0.635 0.2286) (xy -0.635 -0.254) (xy -0.5334 -0.254)
				(xy -0.5334 -0.2794) (xy 0.5334 -0.2794) (xy 0.5334 -0.254) (xy 0.635 -0.254) (xy 0.635 0.254) (xy 0.5334 0.254)
				(xy 0.5334 0.2794)
			)
			(stroke
				(width 0)
				(type default)
			)
			(fill no)
			(layer "F.CrtYd")
		)
		(pad "1" smd rect
			(at 0.40005 0)
			(size 0.4572 0.508)
			(layers "F.Cu" "F.Mask" "F.Paste")
			(net "PSU5_PS_KILL")
		)
		(pad "2" smd rect
			(at -0.40005 0)
			(size 0.4572 0.508)
			(layers "F.Cu" "F.Mask" "F.Paste")
			(net "GND")
		)
	)
)
